M48
INCH,TZ
T01C.001
T02C.01
T03C.012
T04C.014
T05C.01417
T06C.016
T07C.02
T08C.028
T09C.02834
T010C.02913
T011C.037
T012C.053
T013C.086
T014C.087
T015C.093
T016C.094
T017C.097
T018C.111
T019C.119
T020C.138
T021C.14
T022C.166
T023C.168
T024C.225
T025C.404
;EXTENTS: -104.695 -115.867 145.305 120.334 
;LEADER: 12 
;HEADER: 
;CODE  : ASCII 
;FILE  : 16315-1.rou for board 16315-1.brd
%
G90
F1
M16
T022
M16
G00X904920Y-29541
G40
M15
G01Y-21641
M16
G00X15156Y470459
G40
M15
G01Y478359
M16
G00X1894684Y470459
G40
M15
G01Y478359
M16
T019
M16
G00X975787Y-29490
G40
M15
G01Y-21690
M16
G40
M30
